(kicad_pcb
	(version 20260206)
	(generator "pcbnew")
	(generator_version "10.0")
	(general
		(thickness 1.6)
		(legacy_teardrops no)
	)
	(paper "A4")
	(title_block
		(title "04192023_DAF0TMB3IC0_F0TG_MB_C_brd_V02_OCP.brd")
		(comment 1 "Grand Teton / footprints 3060-3066 of 8354")
	)
	(layers
		(0 "F.Cu" signal "TOP")
		(4 "In1.Cu" signal "GND")
		(6 "In2.Cu" signal "IN1")
		(8 "In3.Cu" signal "GND1")
		(10 "In4.Cu" signal "IN2")
		(12 "In5.Cu" signal "GND2")
		(14 "In6.Cu" signal "IN3")
		(16 "In7.Cu" signal "GND3")
		(18 "In8.Cu" signal "VCC")
		(20 "In9.Cu" signal "VCC1")
		(22 "In10.Cu" signal "GND4")
		(24 "In11.Cu" signal "IN4")
		(26 "In12.Cu" signal "GND5")
		(28 "In13.Cu" signal "IN5")
		(30 "In14.Cu" signal "GND6")
		(32 "In15.Cu" signal "IN6")
		(34 "In16.Cu" signal "GND7")
		(2 "B.Cu" signal "BOTTOM")
		(9 "F.Adhes" user "F.Adhesive")
		(11 "B.Adhes" user "B.Adhesive")
		(13 "F.Paste" user "Package Geometry/Pastemask Top")
		(15 "B.Paste" user "Package Geometry/Pastemask Bottom")
		(5 "F.SilkS" user "Ref Des/Silkscreen Top")
		(7 "B.SilkS" user "Ref Des/Silkscreen Bottom")
		(1 "F.Mask" user "Board Geometry/Soldermask Top")
		(3 "B.Mask" user "Board Geometry/Soldermask Bottom")
		(17 "Dwgs.User" user "User.Drawings")
		(19 "Cmts.User" user "User.Comments")
		(21 "Eco1.User" user "User.Eco1")
		(23 "Eco2.User" user "User.Eco2")
		(25 "Edge.Cuts" user "Board Geometry/Outline")
		(27 "Margin" user)
		(31 "F.CrtYd" user "Package Geometry/Place Bound Top")
		(29 "B.CrtYd" user "Package Geometry/Place Bound Bottom")
		(35 "F.Fab" user "Ref Des/Assembly Top")
		(33 "B.Fab" user "Ref Des/Assembly Bottom")
	)
	(footprint ""
		(layer "F.Cu")
		(at 268.197584 -393.91336 -90)
		(property "Reference" "PR2532"
			(at -4.57454 2.978404 90)
			(unlocked yes)
			(layer "F.SilkS")
			(effects
				(font
					(size 0.7874 0.5842)
					(thickness 0.1524)
				)
				(justify left)
			)
		)
		(property "Value" ""
			(at 0 0 270)
			(layer "F.Fab")
			(effects
				(font
					(size 1.27 1.27)
				)
			)
		)
		(duplicate_pad_numbers_are_jumpers no)
		(fp_line
			(start -3.9878 3.5814)
			(end -3.9878 -3.5814)
			(stroke
				(width 0.1524)
				(type default)
			)
			(layer "F.SilkS")
		)
		(fp_line
			(start 3.9878 3.5814)
			(end -3.9878 3.5814)
			(stroke
				(width 0.1524)
				(type default)
			)
			(layer "F.SilkS")
		)
		(fp_line
			(start -3.9878 -3.5814)
			(end 3.9878 -3.5814)
			(stroke
				(width 0.1524)
				(type default)
			)
			(layer "F.SilkS")
		)
		(fp_line
			(start 3.9878 -3.5814)
			(end 3.9878 3.5814)
			(stroke
				(width 0.1524)
				(type default)
			)
			(layer "F.SilkS")
		)
		(fp_line
			(start -3.5306 3.353054)
			(end -3.5306 -3.353054)
			(stroke
				(width 0.1)
				(type default)
			)
			(layer "F.Fab")
		)
		(fp_line
			(start 3.5306 3.353054)
			(end -3.5306 3.353054)
			(stroke
				(width 0.1)
				(type default)
			)
			(layer "F.Fab")
		)
		(fp_line
			(start -3.5306 -3.353054)
			(end 3.5306 -3.353054)
			(stroke
				(width 0.1)
				(type default)
			)
			(layer "F.Fab")
		)
		(fp_line
			(start 3.5306 -3.353054)
			(end 3.5306 3.353054)
			(stroke
				(width 0.1)
				(type default)
			)
			(layer "F.Fab")
		)
		(pad "1A" smd rect
			(at -2.249932 0 90)
			(size 3.2004 6.858)
			(layers "F.Cu" "F.Mask" "F.Paste")
			(net "P12V_PSU")
		)
		(pad "1B" smd rect
			(at -0.776732 0 270)
			(size 0.254 0.508)
			(layers "F.Cu" "F.Mask" "F.Paste")
			(net "P12V_HSC_SENSE2_R2_P")
		)
		(pad "2A" smd rect
			(at 2.249932 0 90)
			(size 3.2004 6.858)
			(layers "F.Cu" "F.Mask" "F.Paste")
			(net "P12V_MAIN_R")
		)
		(pad "2B" smd rect
			(at 0.776732 0 270)
			(size 0.254 0.508)
			(layers "F.Cu" "F.Mask" "F.Paste")
			(net "P12V_HSC_SENSE2_R2_N")
		)
	)
	(footprint ""
		(layer "F.Cu")
		(at 308.002432 -410.406596 90)
		(property "Reference" "C7034"
			(at 0 0 90)
			(layer "F.SilkS")
			(hide yes)
			(effects
				(font
					(size 1.27 1.27)
				)
			)
		)
		(property "Value" ""
			(at 0 0 90)
			(layer "F.Fab")
			(effects
				(font
					(size 1.27 1.27)
				)
			)
		)
		(duplicate_pad_numbers_are_jumpers no)
		(fp_line
			(start 1.524 -0.762)
			(end 1.524 0.762)
			(stroke
				(width 0.1524)
				(type default)
			)
			(layer "F.SilkS")
		)
		(fp_line
			(start -1.524 -0.762)
			(end 1.524 -0.762)
			(stroke
				(width 0.1524)
				(type default)
			)
			(layer "F.SilkS")
		)
		(fp_line
			(start 1.524 0.762)
			(end -1.524 0.762)
			(stroke
				(width 0.1524)
				(type default)
			)
			(layer "F.SilkS")
		)
		(fp_line
			(start -1.524 0.762)
			(end -1.524 -0.762)
			(stroke
				(width 0.1524)
				(type default)
			)
			(layer "F.SilkS")
		)
		(fp_line
			(start 1.1049 -0.724916)
			(end -1.1049 -0.724916)
			(stroke
				(width 0.1)
				(type default)
			)
			(layer "F.Fab")
		)
		(fp_line
			(start -1.1049 -0.724916)
			(end -1.1049 0.724916)
			(stroke
				(width 0.1)
				(type default)
			)
			(layer "F.Fab")
		)
		(fp_line
			(start 1.1049 0.724916)
			(end 1.1049 -0.724916)
			(stroke
				(width 0.1)
				(type default)
			)
			(layer "F.Fab")
		)
		(fp_line
			(start -1.1049 0.724916)
			(end 1.1049 0.724916)
			(stroke
				(width 0.1)
				(type default)
			)
			(layer "F.Fab")
		)
		(pad "1" smd rect
			(at -0.889 0 270)
			(size 1.016 1.27)
			(layers "F.Cu" "F.Mask" "F.Paste")
			(net "P0V9_CPU0_RT_2D")
		)
		(pad "2" smd rect
			(at 0.889 0 270)
			(size 1.016 1.27)
			(layers "F.Cu" "F.Mask" "F.Paste")
			(net "GND")
		)
	)
	(footprint ""
		(layer "F.Cu")
		(at 68.2117 -36.294568)
		(property "Reference" "R4092"
			(at 0 0 0)
			(layer "F.SilkS")
			(hide yes)
			(effects
				(font
					(size 1.27 1.27)
				)
			)
		)
		(property "Value" ""
			(at 0 0 0)
			(layer "F.Fab")
			(effects
				(font
					(size 1.27 1.27)
				)
			)
		)
		(duplicate_pad_numbers_are_jumpers no)
		(fp_line
			(start -0.7874 -0.4064)
			(end 0.7874 -0.4064)
			(stroke
				(width 0.1524)
				(type default)
			)
			(layer "F.SilkS")
		)
		(fp_line
			(start -0.7874 0.4064)
			(end -0.7874 -0.4064)
			(stroke
				(width 0.1524)
				(type default)
			)
			(layer "F.SilkS")
		)
		(fp_line
			(start 0.7874 -0.4064)
			(end 0.7874 0.4064)
			(stroke
				(width 0.1524)
				(type default)
			)
			(layer "F.SilkS")
		)
		(fp_line
			(start 0.7874 0.4064)
			(end -0.7874 0.4064)
			(stroke
				(width 0.1524)
				(type default)
			)
			(layer "F.SilkS")
		)
		(fp_line
			(start -0.67945 -0.305054)
			(end -0.12065 -0.305054)
			(stroke
				(width 0.1)
				(type default)
			)
			(layer "F.Fab")
		)
		(fp_line
			(start -0.67945 0.3048)
			(end -0.67945 -0.305054)
			(stroke
				(width 0.1)
				(type default)
			)
			(layer "F.Fab")
		)
		(fp_line
			(start -0.12065 -0.305054)
			(end -0.12065 -0.2794)
			(stroke
				(width 0.1)
				(type default)
			)
			(layer "F.Fab")
		)
		(fp_line
			(start -0.12065 -0.2794)
			(end 0.12065 -0.2794)
			(stroke
				(width 0.1)
				(type default)
			)
			(layer "F.Fab")
		)
		(fp_line
			(start -0.12065 0.2794)
			(end -0.12065 0.3048)
			(stroke
				(width 0.1)
				(type default)
			)
			(layer "F.Fab")
		)
		(fp_line
			(start -0.12065 0.3048)
			(end -0.67945 0.3048)
			(stroke
				(width 0.1)
				(type default)
			)
			(layer "F.Fab")
		)
		(fp_line
			(start 0.120396 0.2794)
			(end -0.12065 0.2794)
			(stroke
				(width 0.1)
				(type default)
			)
			(layer "F.Fab")
		)
		(fp_line
			(start 0.120396 0.3048)
			(end 0.120396 0.2794)
			(stroke
				(width 0.1)
				(type default)
			)
			(layer "F.Fab")
		)
		(fp_line
			(start 0.12065 -0.3048)
			(end 0.67945 -0.3048)
			(stroke
				(width 0.1)
				(type default)
			)
			(layer "F.Fab")
		)
		(fp_line
			(start 0.12065 -0.2794)
			(end 0.12065 -0.3048)
			(stroke
				(width 0.1)
				(type default)
			)
			(layer "F.Fab")
		)
		(fp_line
			(start 0.67945 -0.3048)
			(end 0.67945 0.3048)
			(stroke
				(width 0.1)
				(type default)
			)
			(layer "F.Fab")
		)
		(fp_line
			(start 0.67945 0.3048)
			(end 0.120396 0.3048)
			(stroke
				(width 0.1)
				(type default)
			)
			(layer "F.Fab")
		)
		(pad "1" smd circle
			(at -0.40005 0)
			(size 0 0)
			(layers "F.Cu" "F.Mask" "F.Paste")
			(net "P3V3_AUX")
		)
		(pad "2" smd circle
			(at 0.40005 0)
			(size 0 0)
			(layers "F.Cu" "F.Mask" "F.Paste")
			(net "OCP_V3_2_P3V3_ADC_ALERT_R")
		)
	)
	(footprint ""
		(layer "F.Cu")
		(at 448.177412 -30.131258 90)
		(property "Reference" "PC2154"
			(at 0 0 90)
			(layer "F.SilkS")
			(hide yes)
			(effects
				(font
					(size 1.27 1.27)
				)
			)
		)
		(property "Value" ""
			(at 0 0 90)
			(layer "F.Fab")
			(effects
				(font
					(size 1.27 1.27)
				)
			)
		)
		(duplicate_pad_numbers_are_jumpers no)
		(fp_line
			(start 0.7874 -0.4064)
			(end 0.7874 0.4064)
			(stroke
				(width 0.1524)
				(type default)
			)
			(layer "F.SilkS")
		)
		(fp_line
			(start -0.7874 -0.4064)
			(end 0.7874 -0.4064)
			(stroke
				(width 0.1524)
				(type default)
			)
			(layer "F.SilkS")
		)
		(fp_line
			(start 0.7874 0.4064)
			(end -0.7874 0.4064)
			(stroke
				(width 0.1524)
				(type default)
			)
			(layer "F.SilkS")
		)
		(fp_line
			(start -0.7874 0.4064)
			(end -0.7874 -0.4064)
			(stroke
				(width 0.1524)
				(type default)
			)
			(layer "F.SilkS")
		)
		(fp_line
			(start -0.12065 -0.305054)
			(end -0.12065 -0.2794)
			(stroke
				(width 0.1)
				(type default)
			)
			(layer "F.Fab")
		)
		(fp_line
			(start -0.67945 -0.305054)
			(end -0.12065 -0.305054)
			(stroke
				(width 0.1)
				(type default)
			)
			(layer "F.Fab")
		)
		(fp_line
			(start 0.67945 -0.3048)
			(end 0.67945 0.3048)
			(stroke
				(width 0.1)
				(type default)
			)
			(layer "F.Fab")
		)
		(fp_line
			(start 0.12065 -0.3048)
			(end 0.67945 -0.3048)
			(stroke
				(width 0.1)
				(type default)
			)
			(layer "F.Fab")
		)
		(fp_line
			(start 0.12065 -0.2794)
			(end 0.12065 -0.3048)
			(stroke
				(width 0.1)
				(type default)
			)
			(layer "F.Fab")
		)
		(fp_line
			(start -0.12065 -0.2794)
			(end 0.12065 -0.2794)
			(stroke
				(width 0.1)
				(type default)
			)
			(layer "F.Fab")
		)
		(fp_line
			(start 0.120396 0.2794)
			(end -0.12065 0.2794)
			(stroke
				(width 0.1)
				(type default)
			)
			(layer "F.Fab")
		)
		(fp_line
			(start -0.12065 0.2794)
			(end -0.12065 0.3048)
			(stroke
				(width 0.1)
				(type default)
			)
			(layer "F.Fab")
		)
		(fp_line
			(start 0.67945 0.3048)
			(end 0.120396 0.3048)
			(stroke
				(width 0.1)
				(type default)
			)
			(layer "F.Fab")
		)
		(fp_line
			(start 0.120396 0.3048)
			(end 0.120396 0.2794)
			(stroke
				(width 0.1)
				(type default)
			)
			(layer "F.Fab")
		)
		(fp_line
			(start -0.12065 0.3048)
			(end -0.67945 0.3048)
			(stroke
				(width 0.1)
				(type default)
			)
			(layer "F.Fab")
		)
		(fp_line
			(start -0.67945 0.3048)
			(end -0.67945 -0.305054)
			(stroke
				(width 0.1)
				(type default)
			)
			(layer "F.Fab")
		)
		(pad "1" smd circle
			(at -0.40005 0 90)
			(size 0 0)
			(layers "F.Cu" "F.Mask" "F.Paste")
			(net "P12V_AUX")
		)
		(pad "2" smd circle
			(at 0.40005 0 90)
			(size 0 0)
			(layers "F.Cu" "F.Mask" "F.Paste")
			(net "GND")
		)
	)
	(footprint ""
		(layer "F.Cu")
		(at 267.896848 -339.218778 90)
		(property "Reference" "PL16"
			(at -3.302 -3.978148 90)
			(unlocked yes)
			(layer "F.SilkS")
			(effects
				(font
					(size 0.7874 0.5842)
					(thickness 0.1524)
				)
				(justify left)
			)
		)
		(property "Value" ""
			(at 0 0 90)
			(layer "F.Fab")
			(effects
				(font
					(size 1.27 1.27)
				)
			)
		)
		(duplicate_pad_numbers_are_jumpers no)
		(fp_line
			(start 3.24993 -3.24993)
			(end 3.24993 -2.2352)
			(stroke
				(width 0.1524)
				(type default)
			)
			(layer "F.SilkS")
		)
		(fp_line
			(start -3.24993 -3.24993)
			(end 3.24993 -3.24993)
			(stroke
				(width 0.1524)
				(type default)
			)
			(layer "F.SilkS")
		)
		(fp_line
			(start -3.24993 -2.2352)
			(end -3.24993 -3.24993)
			(stroke
				(width 0.1524)
				(type default)
			)
			(layer "F.SilkS")
		)
		(fp_line
			(start 3.24993 2.2352)
			(end 3.24993 3.24993)
			(stroke
				(width 0.1524)
				(type default)
			)
			(layer "F.SilkS")
		)
		(fp_line
			(start 3.24993 3.24993)
			(end -3.24993 3.24993)
			(stroke
				(width 0.1524)
				(type default)
			)
			(layer "F.SilkS")
		)
		(fp_line
			(start -3.24993 3.24993)
			(end -3.24993 2.2352)
			(stroke
				(width 0.1524)
				(type default)
			)
			(layer "F.SilkS")
		)
		(fp_line
			(start 3.24993 -3.24993)
			(end 3.24993 3.24993)
			(stroke
				(width 0.1)
				(type default)
			)
			(layer "F.Fab")
		)
		(fp_line
			(start -3.24993 -3.24993)
			(end 3.24993 -3.24993)
			(stroke
				(width 0.1)
				(type default)
			)
			(layer "F.Fab")
		)
		(fp_line
			(start 3.24993 3.24993)
			(end -3.24993 3.24993)
			(stroke
				(width 0.1)
				(type default)
			)
			(layer "F.Fab")
		)
		(fp_line
			(start -3.24993 3.24993)
			(end -3.24993 -3.24993)
			(stroke
				(width 0.1)
				(type default)
			)
			(layer "F.Fab")
		)
		(pad "1" smd rect
			(at -2.29997 0 90)
			(size 2.0066 4.2164)
			(layers "F.Cu" "F.Mask" "F.Paste")
			(net "IND_PVDDIO_P0_CPL0")
		)
		(pad "2" smd rect
			(at 2.29997 0 90)
			(size 2.0066 4.2164)
			(layers "F.Cu" "F.Mask" "F.Paste")
			(net "GND")
		)
	)
	(footprint ""
		(layer "F.Cu")
		(at 365.835692 -255.554988 180)
		(property "Reference" "C2535"
			(at 0 0 180)
			(layer "F.SilkS")
			(hide yes)
			(effects
				(font
					(size 1.27 1.27)
				)
			)
		)
		(property "Value" ""
			(at 0 0 180)
			(layer "F.Fab")
			(effects
				(font
					(size 1.27 1.27)
				)
			)
		)
		(duplicate_pad_numbers_are_jumpers no)
		(fp_line
			(start 0.7874 0.4064)
			(end -0.7874 0.4064)
			(stroke
				(width 0.1524)
				(type default)
			)
			(layer "F.SilkS")
		)
		(fp_line
			(start 0.7874 -0.4064)
			(end 0.7874 0.4064)
			(stroke
				(width 0.1524)
				(type default)
			)
			(layer "F.SilkS")
		)
		(fp_line
			(start -0.7874 0.4064)
			(end -0.7874 -0.4064)
			(stroke
				(width 0.1524)
				(type default)
			)
			(layer "F.SilkS")
		)
		(fp_line
			(start -0.7874 -0.4064)
			(end 0.7874 -0.4064)
			(stroke
				(width 0.1524)
				(type default)
			)
			(layer "F.SilkS")
		)
		(fp_line
			(start 0.67945 0.3048)
			(end 0.120396 0.3048)
			(stroke
				(width 0.1)
				(type default)
			)
			(layer "F.Fab")
		)
		(fp_line
			(start 0.67945 -0.3048)
			(end 0.67945 0.3048)
			(stroke
				(width 0.1)
				(type default)
			)
			(layer "F.Fab")
		)
		(fp_line
			(start 0.12065 -0.2794)
			(end 0.12065 -0.3048)
			(stroke
				(width 0.1)
				(type default)
			)
			(layer "F.Fab")
		)
		(fp_line
			(start 0.12065 -0.3048)
			(end 0.67945 -0.3048)
			(stroke
				(width 0.1)
				(type default)
			)
			(layer "F.Fab")
		)
		(fp_line
			(start 0.120396 0.3048)
			(end 0.120396 0.2794)
			(stroke
				(width 0.1)
				(type default)
			)
			(layer "F.Fab")
		)
		(fp_line
			(start 0.120396 0.2794)
			(end -0.12065 0.2794)
			(stroke
				(width 0.1)
				(type default)
			)
			(layer "F.Fab")
		)
		(fp_line
			(start -0.12065 0.3048)
			(end -0.67945 0.3048)
			(stroke
				(width 0.1)
				(type default)
			)
			(layer "F.Fab")
		)
		(fp_line
			(start -0.12065 0.2794)
			(end -0.12065 0.3048)
			(stroke
				(width 0.1)
				(type default)
			)
			(layer "F.Fab")
		)
		(fp_line
			(start -0.12065 -0.2794)
			(end 0.12065 -0.2794)
			(stroke
				(width 0.1)
				(type default)
			)
			(layer "F.Fab")
		)
		(fp_line
			(start -0.12065 -0.305054)
			(end -0.12065 -0.2794)
			(stroke
				(width 0.1)
				(type default)
			)
			(layer "F.Fab")
		)
		(fp_line
			(start -0.67945 0.3048)
			(end -0.67945 -0.305054)
			(stroke
				(width 0.1)
				(type default)
			)
			(layer "F.Fab")
		)
		(fp_line
			(start -0.67945 -0.305054)
			(end -0.12065 -0.305054)
			(stroke
				(width 0.1)
				(type default)
			)
			(layer "F.Fab")
		)
		(pad "1" smd circle
			(at -0.40005 0 180)
			(size 0 0)
			(layers "F.Cu" "F.Mask" "F.Paste")
			(net "PVDDCR_SOC_P0")
		)
		(pad "2" smd circle
			(at 0.40005 0 180)
			(size 0 0)
			(layers "F.Cu" "F.Mask" "F.Paste")
			(net "GND")
		)
	)
	(footprint ""
		(layer "F.Cu")
		(at 26.545794 -393.317984 90)
		(property "Reference" "PR6629"
			(at 0 0 90)
			(layer "F.SilkS")
			(hide yes)
			(effects
				(font
					(size 1.27 1.27)
				)
			)
		)
		(property "Value" ""
			(at 0 0 90)
			(layer "F.Fab")
			(effects
				(font
					(size 1.27 1.27)
				)
			)
		)
		(duplicate_pad_numbers_are_jumpers no)
		(fp_line
			(start 0.7874 -0.4064)
			(end 0.7874 0.4064)
			(stroke
				(width 0.1524)
				(type default)
			)
			(layer "F.SilkS")
		)
		(fp_line
			(start -0.7874 -0.4064)
			(end 0.7874 -0.4064)
			(stroke
				(width 0.1524)
				(type default)
			)
			(layer "F.SilkS")
		)
		(fp_line
			(start 0.7874 0.4064)
			(end -0.7874 0.4064)
			(stroke
				(width 0.1524)
				(type default)
			)
			(layer "F.SilkS")
		)
		(fp_line
			(start -0.7874 0.4064)
			(end -0.7874 -0.4064)
			(stroke
				(width 0.1524)
				(type default)
			)
			(layer "F.SilkS")
		)
		(fp_line
			(start -0.12065 -0.305054)
			(end -0.12065 -0.2794)
			(stroke
				(width 0.1)
				(type default)
			)
			(layer "F.Fab")
		)
		(fp_line
			(start -0.67945 -0.305054)
			(end -0.12065 -0.305054)
			(stroke
				(width 0.1)
				(type default)
			)
			(layer "F.Fab")
		)
		(fp_line
			(start 0.67945 -0.3048)
			(end 0.67945 0.3048)
			(stroke
				(width 0.1)
				(type default)
			)
			(layer "F.Fab")
		)
		(fp_line
			(start 0.12065 -0.3048)
			(end 0.67945 -0.3048)
			(stroke
				(width 0.1)
				(type default)
			)
			(layer "F.Fab")
		)
		(fp_line
			(start 0.12065 -0.2794)
			(end 0.12065 -0.3048)
			(stroke
				(width 0.1)
				(type default)
			)
			(layer "F.Fab")
		)
		(fp_line
			(start -0.12065 -0.2794)
			(end 0.12065 -0.2794)
			(stroke
				(width 0.1)
				(type default)
			)
			(layer "F.Fab")
		)
		(fp_line
			(start 0.120396 0.2794)
			(end -0.12065 0.2794)
			(stroke
				(width 0.1)
				(type default)
			)
			(layer "F.Fab")
		)
		(fp_line
			(start -0.12065 0.2794)
			(end -0.12065 0.3048)
			(stroke
				(width 0.1)
				(type default)
			)
			(layer "F.Fab")
		)
		(fp_line
			(start 0.67945 0.3048)
			(end 0.120396 0.3048)
			(stroke
				(width 0.1)
				(type default)
			)
			(layer "F.Fab")
		)
		(fp_line
			(start 0.120396 0.3048)
			(end 0.120396 0.2794)
			(stroke
				(width 0.1)
				(type default)
			)
			(layer "F.Fab")
		)
		(fp_line
			(start -0.12065 0.3048)
			(end -0.67945 0.3048)
			(stroke
				(width 0.1)
				(type default)
			)
			(layer "F.Fab")
		)
		(fp_line
			(start -0.67945 0.3048)
			(end -0.67945 -0.305054)
			(stroke
				(width 0.1)
				(type default)
			)
			(layer "F.Fab")
		)
		(pad "1" smd circle
			(at -0.40005 0 90)
			(size 0 0)
			(layers "F.Cu" "F.Mask" "F.Paste")
			(net "SW_P0V9_RETIMER_CPU1_BOOT2")
		)
		(pad "2" smd circle
			(at 0.40005 0 90)
			(size 0 0)
			(layers "F.Cu" "F.Mask" "F.Paste")
			(net "SW_P0V9_RETIMER_CPU1_BOOT2_RC")
		)
	)
)
